# T6G (Grand Teton) — schematic netlist excerpt (pin names and nets, part order shuffled) for the footprints in the layout excerpt that follows; sources: Cadence DE-HDL packaged netlist, KiCad conversion of 04192023_DAF0TMB3IC0_F0TG_MB_C_brd_V02_OCP.brd

PC1856  Q_CAP  22UF 10V 20% X6S  pkg C0805  page 189 : A = P5V_AUX ; B = GND
C2370  Q_CAP  22UF 4V 20% X6S  pkg C0402  page 73 : A = PVDDCR_CPU1_P1 ; B = GND
C92  Q_CAP  0.1UF 25V 10% X7R  pkg 0402  page 87 : A = P3V3_AUX ; B = GND

(kicad_pcb
	(version 20260206)
	(generator "pcbnew")
	(generator_version "10.0")
	(general
		(thickness 1.6)
		(legacy_teardrops no)
	)
	(paper "A4")
	(title_block
		(title "04192023_DAF0TMB3IC0_F0TG_MB_C_brd_V02_OCP.brd")
		(comment 1 "Grand Teton / footprints 7937-7939 of 8354")
	)
	(layers
		(0 "F.Cu" signal "TOP")
		(4 "In1.Cu" signal "GND")
		(6 "In2.Cu" signal "IN1")
		(8 "In3.Cu" signal "GND1")
		(10 "In4.Cu" signal "IN2")
		(12 "In5.Cu" signal "GND2")
		(14 "In6.Cu" signal "IN3")
		(16 "In7.Cu" signal "GND3")
		(18 "In8.Cu" signal "VCC")
		(20 "In9.Cu" signal "VCC1")
		(22 "In10.Cu" signal "GND4")
		(24 "In11.Cu" signal "IN4")
		(26 "In12.Cu" signal "GND5")
		(28 "In13.Cu" signal "IN5")
		(30 "In14.Cu" signal "GND6")
		(32 "In15.Cu" signal "IN6")
		(34 "In16.Cu" signal "GND7")
		(2 "B.Cu" signal "BOTTOM")
		(9 "F.Adhes" user "F.Adhesive")
		(11 "B.Adhes" user "B.Adhesive")
		(13 "F.Paste" user "Package Geometry/Pastemask Top")
		(15 "B.Paste" user "Package Geometry/Pastemask Bottom")
		(5 "F.SilkS" user "Ref Des/Silkscreen Top")
		(7 "B.SilkS" user "Ref Des/Silkscreen Bottom")
		(1 "F.Mask" user "Board Geometry/Soldermask Top")
		(3 "B.Mask" user "Board Geometry/Soldermask Bottom")
		(17 "Dwgs.User" user "User.Drawings")
		(19 "Cmts.User" user "User.Comments")
		(21 "Eco1.User" user "User.Eco1")
		(23 "Eco2.User" user "User.Eco2")
		(25 "Edge.Cuts" user "Board Geometry/Outline")
		(27 "Margin" user)
		(31 "F.CrtYd" user "Package Geometry/Place Bound Top")
		(29 "B.CrtYd" user "Package Geometry/Place Bound Bottom")
		(35 "F.Fab" user "Ref Des/Assembly Top")
		(33 "B.Fab" user "Ref Des/Assembly Bottom")
	)
	(footprint ""
		(layer "B.Cu")
		(at 299.06849 -193.99631)
		(property "Reference" "C92"
			(at 0 0 0)
			(layer "B.SilkS")
			(hide yes)
			(effects
				(font
					(size 1.27 1.27)
				)
				(justify mirror)
			)
		)
		(property "Value" ""
			(at 0 0 0)
			(layer "B.Fab")
			(effects
				(font
					(size 1.27 1.27)
				)
				(justify mirror)
			)
		)
		(duplicate_pad_numbers_are_jumpers no)
		(fp_line
			(start -0.7874 -0.4064)
			(end -0.7874 0.4064)
			(stroke
				(width 0.1524)
				(type default)
			)
			(layer "B.SilkS")
		)
		(fp_line
			(start -0.7874 0.4064)
			(end 0.7874 0.4064)
			(stroke
				(width 0.1524)
				(type default)
			)
			(layer "B.SilkS")
		)
		(fp_line
			(start 0.7874 -0.4064)
			(end -0.7874 -0.4064)
			(stroke
				(width 0.1524)
				(type default)
			)
			(layer "B.SilkS")
		)
		(fp_line
			(start 0.7874 0.4064)
			(end 0.7874 -0.4064)
			(stroke
				(width 0.1524)
				(type default)
			)
			(layer "B.SilkS")
		)
		(fp_line
			(start -0.67945 -0.3048)
			(end -0.67945 0.3048)
			(stroke
				(width 0.1)
				(type default)
			)
			(layer "B.Fab")
		)
		(fp_line
			(start -0.67945 0.3048)
			(end -0.120396 0.3048)
			(stroke
				(width 0.1)
				(type default)
			)
			(layer "B.Fab")
		)
		(fp_line
			(start -0.12065 -0.3048)
			(end -0.67945 -0.3048)
			(stroke
				(width 0.1)
				(type default)
			)
			(layer "B.Fab")
		)
		(fp_line
			(start -0.12065 -0.2794)
			(end -0.12065 -0.3048)
			(stroke
				(width 0.1)
				(type default)
			)
			(layer "B.Fab")
		)
		(fp_line
			(start -0.120396 0.2794)
			(end 0.12065 0.2794)
			(stroke
				(width 0.1)
				(type default)
			)
			(layer "B.Fab")
		)
		(fp_line
			(start -0.120396 0.3048)
			(end -0.120396 0.2794)
			(stroke
				(width 0.1)
				(type default)
			)
			(layer "B.Fab")
		)
		(fp_line
			(start 0.12065 -0.305054)
			(end 0.12065 -0.2794)
			(stroke
				(width 0.1)
				(type default)
			)
			(layer "B.Fab")
		)
		(fp_line
			(start 0.12065 -0.2794)
			(end -0.12065 -0.2794)
			(stroke
				(width 0.1)
				(type default)
			)
			(layer "B.Fab")
		)
		(fp_line
			(start 0.12065 0.2794)
			(end 0.12065 0.3048)
			(stroke
				(width 0.1)
				(type default)
			)
			(layer "B.Fab")
		)
		(fp_line
			(start 0.12065 0.3048)
			(end 0.67945 0.3048)
			(stroke
				(width 0.1)
				(type default)
			)
			(layer "B.Fab")
		)
		(fp_line
			(start 0.67945 -0.305054)
			(end 0.12065 -0.305054)
			(stroke
				(width 0.1)
				(type default)
			)
			(layer "B.Fab")
		)
		(fp_line
			(start 0.67945 0.3048)
			(end 0.67945 -0.305054)
			(stroke
				(width 0.1)
				(type default)
			)
			(layer "B.Fab")
		)
		(pad "1" smd circle
			(at 0.40005 0 180)
			(size 0 0)
			(layers "B.Cu" "B.Mask" "B.Paste")
			(net "P3V3_AUX")
		)
		(pad "2" smd circle
			(at -0.40005 0 180)
			(size 0 0)
			(layers "B.Cu" "B.Mask" "B.Paste")
			(net "GND")
		)
	)
	(footprint ""
		(layer "B.Cu")
		(at 121.960386 -268.418564)
		(property "Reference" "C2370"
			(at 0 0 0)
			(layer "B.SilkS")
			(hide yes)
			(effects
				(font
					(size 1.27 1.27)
				)
				(justify mirror)
			)
		)
		(property "Value" ""
			(at 0 0 0)
			(layer "B.Fab")
			(effects
				(font
					(size 1.27 1.27)
				)
				(justify mirror)
			)
		)
		(duplicate_pad_numbers_are_jumpers no)
		(fp_line
			(start -0.7874 -0.4064)
			(end -0.7874 0.4064)
			(stroke
				(width 0.1524)
				(type default)
			)
			(layer "B.SilkS")
		)
		(fp_line
			(start -0.7874 0.4064)
			(end 0.7874 0.4064)
			(stroke
				(width 0.1524)
				(type default)
			)
			(layer "B.SilkS")
		)
		(fp_line
			(start 0.7874 -0.4064)
			(end -0.7874 -0.4064)
			(stroke
				(width 0.1524)
				(type default)
			)
			(layer "B.SilkS")
		)
		(fp_line
			(start 0.7874 0.4064)
			(end 0.7874 -0.4064)
			(stroke
				(width 0.1524)
				(type default)
			)
			(layer "B.SilkS")
		)
		(fp_line
			(start -0.67945 -0.3048)
			(end -0.67945 0.3048)
			(stroke
				(width 0.1)
				(type default)
			)
			(layer "B.Fab")
		)
		(fp_line
			(start -0.67945 0.3048)
			(end -0.120396 0.3048)
			(stroke
				(width 0.1)
				(type default)
			)
			(layer "B.Fab")
		)
		(fp_line
			(start -0.12065 -0.3048)
			(end -0.67945 -0.3048)
			(stroke
				(width 0.1)
				(type default)
			)
			(layer "B.Fab")
		)
		(fp_line
			(start -0.12065 -0.2794)
			(end -0.12065 -0.3048)
			(stroke
				(width 0.1)
				(type default)
			)
			(layer "B.Fab")
		)
		(fp_line
			(start -0.120396 0.2794)
			(end 0.12065 0.2794)
			(stroke
				(width 0.1)
				(type default)
			)
			(layer "B.Fab")
		)
		(fp_line
			(start -0.120396 0.3048)
			(end -0.120396 0.2794)
			(stroke
				(width 0.1)
				(type default)
			)
			(layer "B.Fab")
		)
		(fp_line
			(start 0.12065 -0.305054)
			(end 0.12065 -0.2794)
			(stroke
				(width 0.1)
				(type default)
			)
			(layer "B.Fab")
		)
		(fp_line
			(start 0.12065 -0.2794)
			(end -0.12065 -0.2794)
			(stroke
				(width 0.1)
				(type default)
			)
			(layer "B.Fab")
		)
		(fp_line
			(start 0.12065 0.2794)
			(end 0.12065 0.3048)
			(stroke
				(width 0.1)
				(type default)
			)
			(layer "B.Fab")
		)
		(fp_line
			(start 0.12065 0.3048)
			(end 0.67945 0.3048)
			(stroke
				(width 0.1)
				(type default)
			)
			(layer "B.Fab")
		)
		(fp_line
			(start 0.67945 -0.305054)
			(end 0.12065 -0.305054)
			(stroke
				(width 0.1)
				(type default)
			)
			(layer "B.Fab")
		)
		(fp_line
			(start 0.67945 0.3048)
			(end 0.67945 -0.305054)
			(stroke
				(width 0.1)
				(type default)
			)
			(layer "B.Fab")
		)
		(pad "1" smd circle
			(at 0.40005 0 180)
			(size 0 0)
			(layers "B.Cu" "B.Mask" "B.Paste")
			(net "PVDDCR_CPU1_P1")
		)
		(pad "2" smd circle
			(at -0.40005 0 180)
			(size 0 0)
			(layers "B.Cu" "B.Mask" "B.Paste")
			(net "GND")
		)
	)
	(footprint ""
		(layer "B.Cu")
		(at 412.256986 -151.346916 90)
		(property "Reference" "PC1856"
			(at 0 0 90)
			(layer "B.SilkS")
			(hide yes)
			(effects
				(font
					(size 1.27 1.27)
				)
				(justify mirror)
			)
		)
		(property "Value" ""
			(at 0 0 90)
			(layer "B.Fab")
			(effects
				(font
					(size 1.27 1.27)
				)
				(justify mirror)
			)
		)
		(duplicate_pad_numbers_are_jumpers no)
		(fp_line
			(start 1.524 -0.762)
			(end -1.524 -0.762)
			(stroke
				(width 0.1524)
				(type default)
			)
			(layer "B.SilkS")
		)
		(fp_line
			(start -1.524 -0.762)
			(end -1.524 0.762)
			(stroke
				(width 0.1524)
				(type default)
			)
			(layer "B.SilkS")
		)
		(fp_line
			(start 1.524 0.762)
			(end 1.524 -0.762)
			(stroke
				(width 0.1524)
				(type default)
			)
			(layer "B.SilkS")
		)
		(fp_line
			(start -1.524 0.762)
			(end 1.524 0.762)
			(stroke
				(width 0.1524)
				(type default)
			)
			(layer "B.SilkS")
		)
		(fp_line
			(start 1.1049 -0.724916)
			(end 1.1049 0.724916)
			(stroke
				(width 0.1)
				(type default)
			)
			(layer "B.Fab")
		)
		(fp_line
			(start -1.1049 -0.724916)
			(end 1.1049 -0.724916)
			(stroke
				(width 0.1)
				(type default)
			)
			(layer "B.Fab")
		)
		(fp_line
			(start 1.1049 0.724916)
			(end -1.1049 0.724916)
			(stroke
				(width 0.1)
				(type default)
			)
			(layer "B.Fab")
		)
		(fp_line
			(start -1.1049 0.724916)
			(end -1.1049 -0.724916)
			(stroke
				(width 0.1)
				(type default)
			)
			(layer "B.Fab")
		)
		(pad "1" smd rect
			(at 0.889 0 90)
			(size 1.016 1.27)
			(layers "B.Cu" "B.Mask" "B.Paste")
			(net "P5V_AUX")
		)
		(pad "2" smd rect
			(at -0.889 0 90)
			(size 1.016 1.27)
			(layers "B.Cu" "B.Mask" "B.Paste")
			(net "GND")
		)
	)
)
